(kicad_pcb
	(version 20241229)
	(generator "pcbnew")
	(generator_version "9.0")
	(general
		(thickness 1.63)
		(legacy_teardrops no)
	)
	(paper "A4")
	(title_block
		(title "CM4 Baseboard")
		(date "2026-01-05")
		(rev "1.1.1")
		(company "Antmicro Ltd")
		(comment 1 "www.antmicro.com")
		(comment 9 "footprints 103-107 of 506")
	)
	(layers
		(0 "F.Cu" signal)
		(4 "In1.Cu" power)
		(6 "In2.Cu" power)
		(8 "In3.Cu" signal)
		(10 "In4.Cu" signal)
		(2 "B.Cu" signal)
		(9 "F.Adhes" user "F.Adhesive")
		(11 "B.Adhes" user "B.Adhesive")
		(13 "F.Paste" user)
		(15 "B.Paste" user)
		(5 "F.SilkS" user "F.Silkscreen")
		(7 "B.SilkS" user "B.Silkscreen")
		(1 "F.Mask" user)
		(3 "B.Mask" user)
		(17 "Dwgs.User" user "User.Drawings")
		(19 "Cmts.User" user "User.Comments")
		(21 "Eco1.User" user "User.Eco1")
		(23 "Eco2.User" user "User.Eco2")
		(25 "Edge.Cuts" user)
		(27 "Margin" user)
		(31 "F.CrtYd" user "F.Courtyard")
		(29 "B.CrtYd" user "B.Courtyard")
		(35 "F.Fab" user)
		(33 "B.Fab" user)
	)
	(footprint "antmicro-footprints:C_0402_1005Metric"
		(layer "F.Cu")
		(at 87.367962 153.2665 -90)
		(descr "Capacitor SMD 0402")
		(tags "capacitor SMD 0402")
		(property "Reference" "C203"
			(at 0.03 -1.42 90)
			(layer "F.SilkS")
			(effects
				(font
					(size 0.7 0.7)
					(thickness 0.15)
				)
				(justify right bottom)
			)
		)
		(property "Value" "C_100n_0402"
			(at -1.022927 2.155213 90)
			(layer "F.Fab")
			(effects
				(font
					(size 0.7 0.7)
					(thickness 0.15)
				)
				(justify right bottom)
			)
		)
		(property "Datasheet" "https://www.murata.com/products/productdetail?partno=GRM155R61H104KE14%23"
			(at 0 0 270)
			(layer "F.Fab")
			(hide yes)
			(effects
				(font
					(size 1.27 1.27)
					(thickness 0.15)
				)
			)
		)
		(property "MPN" "GRM155R61H104KE14D"
			(at 0 0 270)
			(unlocked yes)
			(layer "F.Fab")
			(hide yes)
			(effects
				(font
					(size 1 1)
					(thickness 0.15)
				)
			)
		)
		(property "Manufacturer" "Murata"
			(at 0 0 270)
			(unlocked yes)
			(layer "F.Fab")
			(hide yes)
			(effects
				(font
					(size 1 1)
					(thickness 0.15)
				)
			)
		)
		(property "License" "Apache-2.0"
			(at 0 0 270)
			(unlocked yes)
			(layer "F.Fab")
			(hide yes)
			(effects
				(font
					(size 1 1)
					(thickness 0.15)
				)
			)
		)
		(property "Author" "Antmicro"
			(at 0 0 270)
			(unlocked yes)
			(layer "F.Fab")
			(hide yes)
			(effects
				(font
					(size 1 1)
					(thickness 0.15)
				)
			)
		)
		(property "Val" "100n"
			(at 0 0 270)
			(unlocked yes)
			(layer "F.Fab")
			(hide yes)
			(effects
				(font
					(size 1 1)
					(thickness 0.15)
				)
			)
		)
		(property "Voltage" "50V"
			(at 0 0 270)
			(unlocked yes)
			(layer "F.Fab")
			(hide yes)
			(effects
				(font
					(size 1 1)
					(thickness 0.15)
				)
			)
		)
		(property "Dielectric" "X5R"
			(at 0 0 270)
			(unlocked yes)
			(layer "F.Fab")
			(hide yes)
			(effects
				(font
					(size 1 1)
					(thickness 0.15)
				)
			)
		)
		(sheetname "/Compute module/")
		(sheetfile "compute-module.kicad_sch")
		(attr smd)
		(fp_rect
			(start -0.925 -0.47)
			(end 0.925 0.47)
			(stroke
				(width 0.05)
				(type default)
			)
			(fill no)
			(layer "F.CrtYd")
		)
		(fp_line
			(start -0.494 0.248)
			(end -0.494 -0.25)
			(stroke
				(width 0.15)
				(type solid)
			)
			(layer "F.Fab")
		)
		(fp_line
			(start 0.504 0.248)
			(end -0.494 0.248)
			(stroke
				(width 0.15)
				(type solid)
			)
			(layer "F.Fab")
		)
		(fp_line
			(start -0.494 -0.25)
			(end 0.504 -0.25)
			(stroke
				(width 0.15)
				(type solid)
			)
			(layer "F.Fab")
		)
		(fp_line
			(start 0.504 -0.25)
			(end 0.504 0.248)
			(stroke
				(width 0.15)
				(type solid)
			)
			(layer "F.Fab")
		)
		(fp_text user "Author: Antmicro"
			(at -0.939 3.399 270)
			(layer "F.Fab")
			(effects
				(font
					(size 0.7 0.7)
					(thickness 0.15)
				)
				(justify left bottom)
			)
		)
		(fp_text user "License: Apache-2.0"
			(at -0.939 5.799 270)
			(layer "F.Fab")
			(effects
				(font
					(size 0.7 0.7)
					(thickness 0.15)
				)
				(justify left bottom)
			)
		)
		(fp_text user "${REFERENCE}"
			(at -0.939 4.599 270)
			(layer "F.Fab")
			(effects
				(font
					(size 0.7 0.7)
					(thickness 0.15)
				)
				(justify left bottom)
			)
		)
		(pad "1" smd roundrect
			(at -0.48 0 270)
			(size 0.59 0.64)
			(layers "F.Cu" "F.Mask" "F.Paste")
			(roundrect_rratio 0.25)
			(net 3 "GND")
			(pintype "passive")
		)
		(pad "2" smd roundrect
			(at 0.48 0 270)
			(size 0.59 0.64)
			(layers "F.Cu" "F.Mask" "F.Paste")
			(roundrect_rratio 0.25)
			(net 18 "V_{IO}")
			(pintype "passive")
		)
	)
	(footprint "antmicro-footprints:Nexperia_DFN-10_2.5x1mm_P0.5mm"
		(layer "F.Cu")
		(at 134.067962 150.1285 90)
		(property "Reference" "D807"
			(at -1.298 -1.562 90)
			(layer "F.SilkS")
			(effects
				(font
					(size 0.7 0.7)
					(thickness 0.15)
				)
				(justify left bottom)
			)
		)
		(property "Value" "PUSB3F96X_PASS"
			(at -0.016 1.705 90)
			(layer "F.Fab")
			(effects
				(font
					(size 0.7 0.7)
					(thickness 0.15)
				)
				(justify left bottom)
			)
		)
		(property "Datasheet" "https://mouser.com/datasheet/2/916/PUSB3F96-1600324.pdf"
			(at 0 0 90)
			(layer "F.Fab")
			(hide yes)
			(effects
				(font
					(size 1.27 1.27)
					(thickness 0.15)
				)
			)
		)
		(property "Manufacturer" "Nexperia"
			(at 0 0 90)
			(unlocked yes)
			(layer "F.Fab")
			(hide yes)
			(effects
				(font
					(size 1 1)
					(thickness 0.15)
				)
			)
		)
		(property "MPN" "PUSB3F96X"
			(at 0 0 90)
			(unlocked yes)
			(layer "F.Fab")
			(hide yes)
			(effects
				(font
					(size 1 1)
					(thickness 0.15)
				)
			)
		)
		(property "Author" "Antmicro"
			(at 0 0 90)
			(unlocked yes)
			(layer "F.Fab")
			(hide yes)
			(effects
				(font
					(size 1 1)
					(thickness 0.15)
				)
			)
		)
		(property "License" "Apache-2.0"
			(at 0 0 90)
			(unlocked yes)
			(layer "F.Fab")
			(hide yes)
			(effects
				(font
					(size 1 1)
					(thickness 0.15)
				)
			)
		)
		(sheetname "/Peripherals/")
		(sheetfile "peripherals.kicad_sch")
		(attr smd)
		(fp_line
			(start -1.375 -0.4)
			(end -1.375 0.4)
			(stroke
				(width 0.15)
				(type solid)
			)
			(layer "F.SilkS")
		)
		(fp_line
			(start 1.375 0.4)
			(end 1.375 -0.4)
			(stroke
				(width 0.15)
				(type solid)
			)
			(layer "F.SilkS")
		)
		(fp_circle
			(center -1.4 0.7)
			(end -1.349 0.7)
			(stroke
				(width 0.15)
				(type solid)
			)
			(fill yes)
			(layer "F.SilkS")
		)
		(fp_rect
			(start -1.4 -0.725)
			(end 1.4 0.725)
			(stroke
				(width 0.05)
				(type solid)
			)
			(fill no)
			(layer "F.CrtYd")
		)
		(fp_line
			(start 1.25 -0.5)
			(end -1.25 -0.5)
			(stroke
				(width 0.15)
				(type solid)
			)
			(layer "F.Fab")
		)
		(fp_line
			(start -1.25 -0.5)
			(end -1.25 0.15)
			(stroke
				(width 0.15)
				(type solid)
			)
			(layer "F.Fab")
		)
		(fp_line
			(start -1.25 0.15)
			(end -0.9 0.5)
			(stroke
				(width 0.15)
				(type solid)
			)
			(layer "F.Fab")
		)
		(fp_line
			(start 1.25 0.5)
			(end 1.25 -0.5)
			(stroke
				(width 0.15)
				(type solid)
			)
			(layer "F.Fab")
		)
		(fp_line
			(start -0.9 0.5)
			(end 1.25 0.5)
			(stroke
				(width 0.15)
				(type solid)
			)
			(layer "F.Fab")
		)
		(fp_text user "License: Apache-2.0"
			(at -1.367 6.105 90)
			(layer "F.Fab")
			(effects
				(font
					(size 0.7 0.7)
					(thickness 0.15)
				)
				(justify left bottom)
			)
		)
		(fp_text user "Author: Antmicro"
			(at -1.367 4.905 90)
			(layer "F.Fab")
			(effects
				(font
					(size 0.7 0.7)
					(thickness 0.15)
				)
				(justify left bottom)
			)
		)
		(fp_text user "${REFERENCE}"
			(at -1.367 3.704 90)
			(layer "F.Fab")
			(effects
				(font
					(size 0.7 0.7)
					(thickness 0.15)
				)
				(justify left bottom)
			)
		)
		(pad "1" smd rect
			(at -1 0.3875 90)
			(size 0.2 0.475)
			(layers "F.Cu" "F.Mask" "F.Paste")
			(net 10 "+5V")
			(pinfunction "CH1")
			(pintype "passive")
			(solder_mask_margin 0.05)
		)
		(pad "2" smd rect
			(at -0.5 0.3875 90)
			(size 0.2 0.475)
			(layers "F.Cu" "F.Mask" "F.Paste")
			(net 239 "/Compute module/GPIO.14{slash}RXD0")
			(pinfunction "CH2")
			(pintype "passive")
			(solder_mask_margin 0.05)
		)
		(pad "3" smd rect
			(at 0 0.3875 90)
			(size 0.2 0.475)
			(layers "F.Cu" "F.Mask" "F.Paste")
			(net 3 "GND")
			(pinfunction "GND")
			(pintype "passive")
			(solder_mask_margin 0.05)
		)
		(pad "4" smd rect
			(at 0.5 0.3875 90)
			(size 0.2 0.475)
			(layers "F.Cu" "F.Mask" "F.Paste")
			(net 241 "/Compute module/GPIO.15{slash}TXD0")
			(pinfunction "CH3")
			(pintype "passive")
			(solder_mask_margin 0.05)
		)
		(pad "5" smd rect
			(at 1 0.3875 90)
			(size 0.2 0.475)
			(layers "F.Cu" "F.Mask" "F.Paste")
			(net 237 "/Compute module/GPIO.18")
			(pinfunction "CH4")
			(pintype "passive")
			(solder_mask_margin 0.05)
		)
		(pad "6" smd rect
			(at 1 -0.3875 90)
			(size 0.2 0.475)
			(layers "F.Cu" "F.Mask" "F.Paste")
			(net 237 "/Compute module/GPIO.18")
			(pinfunction "CH4")
			(pintype "passive")
			(solder_mask_margin 0.05)
		)
		(pad "7" smd rect
			(at 0.5 -0.3875 90)
			(size 0.2 0.475)
			(layers "F.Cu" "F.Mask" "F.Paste")
			(net 241 "/Compute module/GPIO.15{slash}TXD0")
			(pinfunction "CH3")
			(pintype "passive")
			(solder_mask_margin 0.05)
		)
		(pad "8" smd rect
			(at 0 -0.3875 90)
			(size 0.2 0.475)
			(layers "F.Cu" "F.Mask" "F.Paste")
			(net 3 "GND")
			(pinfunction "GND")
			(pintype "passive")
			(solder_mask_margin 0.05)
		)
		(pad "9" smd rect
			(at -0.501 -0.3875 90)
			(size 0.2 0.475)
			(layers "F.Cu" "F.Mask" "F.Paste")
			(net 239 "/Compute module/GPIO.14{slash}RXD0")
			(pinfunction "CH2")
			(pintype "passive")
			(solder_mask_margin 0.05)
		)
		(pad "10" smd rect
			(at -1 -0.3875 90)
			(size 0.2 0.475)
			(layers "F.Cu" "F.Mask" "F.Paste")
			(net 10 "+5V")
			(pinfunction "CH1")
			(pintype "passive")
			(solder_mask_margin 0.05)
		)
	)
	(footprint "antmicro-footprints:R_0402_1005Metric"
		(layer "F.Cu")
		(at 66.925 167.275 180)
		(descr "Resistor SMD 0402")
		(tags "resistor SMD 0402")
		(property "Reference" "R3"
			(at 0.85 0.375 0)
			(layer "F.SilkS")
			(effects
				(font
					(size 0.7 0.7)
					(thickness 0.15)
				)
				(justify right top)
			)
		)
		(property "Value" "R_0R_0402"
			(at -1.011843 1.772047 0)
			(layer "F.Fab")
			(effects
				(font
					(size 0.7 0.7)
					(thickness 0.15)
				)
				(justify right top)
			)
		)
		(property "Datasheet" "https://industrial.panasonic.com/cdbs/www-data/pdf/RDA0000/AOA0000C301.pdf"
			(at 0 0 0)
			(layer "F.Fab")
			(hide yes)
			(effects
				(font
					(size 1.27 1.27)
					(thickness 0.15)
				)
			)
		)
		(property "Description" "SMD Chip Resistor, Jumper, 0 ohm, 100 mW, 0402 [1005 Metric], Thick Film, General Purpose"
			(at 0 0 0)
			(layer "F.Fab")
			(hide yes)
			(effects
				(font
					(size 1.27 1.27)
					(thickness 0.15)
				)
			)
		)
		(property "MPN" "ERJ2GE0R00X"
			(at 0 0 180)
			(unlocked yes)
			(layer "F.Fab")
			(hide yes)
			(effects
				(font
					(size 1 1)
					(thickness 0.15)
				)
			)
		)
		(property "Manufacturer" "Panasonic"
			(at 0 0 180)
			(unlocked yes)
			(layer "F.Fab")
			(hide yes)
			(effects
				(font
					(size 1 1)
					(thickness 0.15)
				)
			)
		)
		(property "License" "Apache-2.0"
			(at 0 0 180)
			(unlocked yes)
			(layer "F.Fab")
			(hide yes)
			(effects
				(font
					(size 1 1)
					(thickness 0.15)
				)
			)
		)
		(property "Author" "Antmicro"
			(at 0 0 180)
			(unlocked yes)
			(layer "F.Fab")
			(hide yes)
			(effects
				(font
					(size 1 1)
					(thickness 0.15)
				)
			)
		)
		(property "Val" "0R"
			(at 0 0 180)
			(unlocked yes)
			(layer "F.Fab")
			(hide yes)
			(effects
				(font
					(size 1 1)
					(thickness 0.15)
				)
			)
		)
		(property "Tolerance" "~"
			(at 0 0 180)
			(unlocked yes)
			(layer "F.Fab")
			(hide yes)
			(effects
				(font
					(size 1 1)
					(thickness 0.15)
				)
			)
		)
		(property "Current" "1A"
			(at 0 0 180)
			(unlocked yes)
			(layer "F.Fab")
			(hide yes)
			(effects
				(font
					(size 1 1)
					(thickness 0.15)
				)
			)
		)
		(sheetname "/Peripherals/")
		(sheetfile "peripherals.kicad_sch")
		(attr smd)
		(fp_rect
			(start -0.925 -0.47)
			(end 0.925 0.47)
			(stroke
				(width 0.05)
				(type default)
			)
			(fill no)
			(layer "F.CrtYd")
		)
		(fp_rect
			(start -0.5 -0.25)
			(end 0.5 0.25)
			(stroke
				(width 0.15)
				(type solid)
			)
			(fill no)
			(layer "F.Fab")
		)
		(fp_text user "Author: Antmicro"
			(at -0.95 4.169 0)
			(layer "F.Fab")
			(effects
				(font
					(size 0.7 0.7)
					(thickness 0.15)
				)
				(justify right top)
			)
		)
		(fp_text user "${REFERENCE}"
			(at -0.95 3.168 0)
			(layer "F.Fab")
			(effects
				(font
					(size 0.7 0.7)
					(thickness 0.15)
				)
				(justify right top)
			)
		)
		(fp_text user "License: Apache-2.0"
			(at -0.95 5.169 0)
			(layer "F.Fab")
			(effects
				(font
					(size 0.7 0.7)
					(thickness 0.15)
				)
				(justify right top)
			)
		)
		(pad "1" smd roundrect
			(at -0.48 0 180)
			(size 0.59 0.64)
			(layers "F.Cu" "F.Mask" "F.Paste")
			(roundrect_rratio 0.25)
			(net 501 "Net-(U801-V_{DD(UP)})")
			(pintype "passive")
		)
		(pad "2" smd roundrect
			(at 0.48 0 180)
			(size 0.59 0.64)
			(layers "F.Cu" "F.Mask" "F.Paste")
			(roundrect_rratio 0.25)
			(net 10 "+5V")
			(pintype "passive")
		)
	)
	(footprint "antmicro-footprints:C_0402_1005Metric"
		(layer "F.Cu")
		(at 83.442962 138.157236 180)
		(descr "Capacitor SMD 0402")
		(tags "capacitor SMD 0402")
		(property "Reference" "C923"
			(at 1.025 -0.779264 0)
			(layer "F.SilkS")
			(effects
				(font
					(size 0.7 0.7)
					(thickness 0.15)
				)
				(justify right bottom)
			)
		)
		(property "Value" "C_100n_0402"
			(at -1.022927 2.155213 0)
			(layer "F.Fab")
			(effects
				(font
					(size 0.7 0.7)
					(thickness 0.15)
				)
				(justify right bottom)
			)
		)
		(property "Datasheet" "https://www.murata.com/products/productdetail?partno=GRM155R61H104KE14%23"
			(at 0 0 180)
			(layer "F.Fab")
			(hide yes)
			(effects
				(font
					(size 1.27 1.27)
					(thickness 0.15)
				)
			)
		)
		(property "Manufacturer" "Murata"
			(at 0 0 180)
			(unlocked yes)
			(layer "F.Fab")
			(hide yes)
			(effects
				(font
					(size 1 1)
					(thickness 0.15)
				)
			)
		)
		(property "MPN" "GRM155R61H104KE14D"
			(at 0 0 180)
			(unlocked yes)
			(layer "F.Fab")
			(hide yes)
			(effects
				(font
					(size 1 1)
					(thickness 0.15)
				)
			)
		)
		(property "Val" "100n"
			(at 0 0 180)
			(unlocked yes)
			(layer "F.Fab")
			(hide yes)
			(effects
				(font
					(size 1 1)
					(thickness 0.15)
				)
			)
		)
		(property "License" "Apache-2.0"
			(at 0 0 180)
			(unlocked yes)
			(layer "F.Fab")
			(hide yes)
			(effects
				(font
					(size 1 1)
					(thickness 0.15)
				)
			)
		)
		(property "Author" "Antmicro"
			(at 0 0 180)
			(unlocked yes)
			(layer "F.Fab")
			(hide yes)
			(effects
				(font
					(size 1 1)
					(thickness 0.15)
				)
			)
		)
		(property "Voltage" "50V"
			(at 0 0 180)
			(unlocked yes)
			(layer "F.Fab")
			(hide yes)
			(effects
				(font
					(size 1 1)
					(thickness 0.15)
				)
			)
		)
		(property "Dielectric" "X5R"
			(at 0 0 180)
			(unlocked yes)
			(layer "F.Fab")
			(hide yes)
			(effects
				(font
					(size 1 1)
					(thickness 0.15)
				)
			)
		)
		(sheetname "/USB/")
		(sheetfile "usb.kicad_sch")
		(attr smd)
		(fp_rect
			(start -0.925 -0.47)
			(end 0.925 0.47)
			(stroke
				(width 0.05)
				(type default)
			)
			(fill no)
			(layer "F.CrtYd")
		)
		(fp_line
			(start 0.504 0.248)
			(end -0.494 0.248)
			(stroke
				(width 0.15)
				(type solid)
			)
			(layer "F.Fab")
		)
		(fp_line
			(start 0.504 -0.25)
			(end 0.504 0.248)
			(stroke
				(width 0.15)
				(type solid)
			)
			(layer "F.Fab")
		)
		(fp_line
			(start -0.494 0.248)
			(end -0.494 -0.25)
			(stroke
				(width 0.15)
				(type solid)
			)
			(layer "F.Fab")
		)
		(fp_line
			(start -0.494 -0.25)
			(end 0.504 -0.25)
			(stroke
				(width 0.15)
				(type solid)
			)
			(layer "F.Fab")
		)
		(fp_text user "Author: Antmicro"
			(at -0.939 3.399 180)
			(layer "F.Fab")
			(effects
				(font
					(size 0.7 0.7)
					(thickness 0.15)
				)
				(justify left bottom)
			)
		)
		(fp_text user "${REFERENCE}"
			(at -0.939 4.599 180)
			(layer "F.Fab")
			(effects
				(font
					(size 0.7 0.7)
					(thickness 0.15)
				)
				(justify left bottom)
			)
		)
		(fp_text user "License: Apache-2.0"
			(at -0.939 5.799 180)
			(layer "F.Fab")
			(effects
				(font
					(size 0.7 0.7)
					(thickness 0.15)
				)
				(justify left bottom)
			)
		)
		(pad "1" smd roundrect
			(at -0.48 0 180)
			(size 0.59 0.64)
			(layers "F.Cu" "F.Mask" "F.Paste")
			(roundrect_rratio 0.25)
			(net 30 "/USB/USB_1V2")
			(pintype "passive")
		)
		(pad "2" smd roundrect
			(at 0.48 0 180)
			(size 0.59 0.64)
			(layers "F.Cu" "F.Mask" "F.Paste")
			(roundrect_rratio 0.25)
			(net 3 "GND")
			(pintype "passive")
		)
	)
	(footprint "antmicro-footprints:TP_SMD_0.75mm"
		(layer "F.Cu")
		(at 76.967962 162.6915 180)
		(property "Reference" "TP205"
			(at 9.19 0.515 0)
			(layer "F.SilkS")
			(effects
				(font
					(size 0.7 0.7)
					(thickness 0.15)
				)
				(justify right bottom)
			)
		)
		(property "Value" "TP_0.75mm_SMD"
			(at 0 1.2 0)
			(layer "F.Fab")
			(effects
				(font
					(size 0.7 0.7)
					(thickness 0.15)
				)
				(justify right bottom)
			)
		)
		(property "Author" "Antmicro"
			(at 0 0 180)
			(unlocked yes)
			(layer "F.Fab")
			(hide yes)
			(effects
				(font
					(size 1 1)
					(thickness 0.15)
				)
			)
		)
		(property "License" "Apache-2.0"
			(at 0 0 180)
			(unlocked yes)
			(layer "F.Fab")
			(hide yes)
			(effects
				(font
					(size 1 1)
					(thickness 0.15)
				)
			)
		)
		(property "MPN" ""
			(at 0 0 180)
			(unlocked yes)
			(layer "F.Fab")
			(hide yes)
			(effects
				(font
					(size 1 1)
					(thickness 0.15)
				)
			)
		)
		(property "Manufacturer" ""
			(at 0 0 180)
			(unlocked yes)
			(layer "F.Fab")
			(hide yes)
			(effects
				(font
					(size 1 1)
					(thickness 0.15)
				)
			)
		)
		(sheetname "/Compute module/")
		(sheetfile "compute-module.kicad_sch")
		(attr exclude_from_pos_files exclude_from_bom)
		(fp_circle
			(center 0 0)
			(end 0.475 0)
			(stroke
				(width 0.05)
				(type default)
			)
			(fill no)
			(layer "F.CrtYd")
		)
		(fp_text user "${REFERENCE}"
			(at -0.4 2.7 180)
			(layer "F.Fab")
			(effects
				(font
					(size 0.7 0.7)
					(thickness 0.15)
				)
				(justify left bottom)
			)
		)
		(fp_text user "License: Apache-2.0"
			(at -0.4 5.101 180)
			(layer "F.Fab")
			(effects
				(font
					(size 0.7 0.7)
					(thickness 0.15)
				)
				(justify left bottom)
			)
		)
		(fp_text user "Author: Antmicro"
			(at -0.4 3.901 180)
			(layer "F.Fab")
			(effects
				(font
					(size 0.7 0.7)
					(thickness 0.15)
				)
				(justify left bottom)
			)
		)
		(pad "1" smd circle
			(at 0 0 180)
			(size 0.75 0.75)
			(layers "F.Cu" "F.Mask")
			(net 247 "/Compute module/WL_nDis")
			(pinfunction "1")
			(pintype "passive")
		)
	)
)
